(kicad_pcb
	(version 20260206)
	(generator "pcbnew")
	(generator_version "10.0")
	(general
		(thickness 1.6)
		(legacy_teardrops no)
	)
	(paper "A4")
	(title_block
		(title "01162023_DA0F0TEBIF0_F0T_Expander_BD_F_brd_V02_OCP.brd")
		(comment 1 "Grand Teton / footprints 2962-2968 of 9728")
	)
	(layers
		(0 "F.Cu" signal "TOP")
		(4 "In1.Cu" signal "GND")
		(6 "In2.Cu" signal "VCC")
		(8 "In3.Cu" signal "VCC1")
		(10 "In4.Cu" signal "GND1")
		(12 "In5.Cu" signal "IN1")
		(14 "In6.Cu" signal "GND2")
		(16 "In7.Cu" signal "IN2")
		(18 "In8.Cu" signal "GND3")
		(20 "In9.Cu" signal "IN3")
		(22 "In10.Cu" signal "GND4")
		(24 "In11.Cu" signal "IN4")
		(26 "In12.Cu" signal "GND5")
		(28 "In13.Cu" signal "IN5")
		(30 "In14.Cu" signal "GND6")
		(32 "In15.Cu" signal "IN6")
		(34 "In16.Cu" signal "GND7")
		(2 "B.Cu" signal "BOTTOM")
		(9 "F.Adhes" user "F.Adhesive")
		(11 "B.Adhes" user "B.Adhesive")
		(13 "F.Paste" user "Package Geometry/Pastemask Top")
		(15 "B.Paste" user "Package Geometry/Pastemask Bottom")
		(5 "F.SilkS" user "Ref Des/Silkscreen Top")
		(7 "B.SilkS" user "Ref Des/Silkscreen Bottom")
		(1 "F.Mask" user "Board Geometry/Soldermask Top")
		(3 "B.Mask" user "Board Geometry/Soldermask Bottom")
		(17 "Dwgs.User" user "User.Drawings")
		(19 "Cmts.User" user "User.Comments")
		(21 "Eco1.User" user "User.Eco1")
		(23 "Eco2.User" user "User.Eco2")
		(25 "Edge.Cuts" user "Board Geometry/Outline")
		(27 "Margin" user)
		(31 "F.CrtYd" user "Package Geometry/Place Bound Top")
		(29 "B.CrtYd" user "Package Geometry/Place Bound Bottom")
		(35 "F.Fab" user "Ref Des/Assembly Top")
		(33 "B.Fab" user "Ref Des/Assembly Bottom")
	)
	(footprint ""
		(layer "F.Cu")
		(at 27.126184 -37.929566 90)
		(property "Reference" "R5543"
			(at 0 0 90)
			(layer "F.SilkS")
			(hide yes)
			(effects
				(font
					(size 1.27 1.27)
				)
			)
		)
		(property "Value" ""
			(at 0 0 90)
			(layer "F.Fab")
			(effects
				(font
					(size 1.27 1.27)
				)
			)
		)
		(duplicate_pad_numbers_are_jumpers no)
		(fp_line
			(start 0.7874 -0.4064)
			(end 0.7874 0.4064)
			(stroke
				(width 0.1524)
				(type default)
			)
			(layer "F.SilkS")
		)
		(fp_line
			(start -0.7874 -0.4064)
			(end 0.7874 -0.4064)
			(stroke
				(width 0.1524)
				(type default)
			)
			(layer "F.SilkS")
		)
		(fp_line
			(start 0.7874 0.4064)
			(end -0.7874 0.4064)
			(stroke
				(width 0.1524)
				(type default)
			)
			(layer "F.SilkS")
		)
		(fp_line
			(start -0.7874 0.4064)
			(end -0.7874 -0.4064)
			(stroke
				(width 0.1524)
				(type default)
			)
			(layer "F.SilkS")
		)
		(fp_line
			(start -0.12065 -0.305054)
			(end -0.12065 -0.2794)
			(stroke
				(width 0.1)
				(type default)
			)
			(layer "F.Fab")
		)
		(fp_line
			(start -0.67945 -0.305054)
			(end -0.12065 -0.305054)
			(stroke
				(width 0.1)
				(type default)
			)
			(layer "F.Fab")
		)
		(fp_line
			(start 0.67945 -0.3048)
			(end 0.67945 0.3048)
			(stroke
				(width 0.1)
				(type default)
			)
			(layer "F.Fab")
		)
		(fp_line
			(start 0.12065 -0.3048)
			(end 0.67945 -0.3048)
			(stroke
				(width 0.1)
				(type default)
			)
			(layer "F.Fab")
		)
		(fp_line
			(start 0.12065 -0.2794)
			(end 0.12065 -0.3048)
			(stroke
				(width 0.1)
				(type default)
			)
			(layer "F.Fab")
		)
		(fp_line
			(start -0.12065 -0.2794)
			(end 0.12065 -0.2794)
			(stroke
				(width 0.1)
				(type default)
			)
			(layer "F.Fab")
		)
		(fp_line
			(start 0.120396 0.2794)
			(end -0.12065 0.2794)
			(stroke
				(width 0.1)
				(type default)
			)
			(layer "F.Fab")
		)
		(fp_line
			(start -0.12065 0.2794)
			(end -0.12065 0.3048)
			(stroke
				(width 0.1)
				(type default)
			)
			(layer "F.Fab")
		)
		(fp_line
			(start 0.67945 0.3048)
			(end 0.120396 0.3048)
			(stroke
				(width 0.1)
				(type default)
			)
			(layer "F.Fab")
		)
		(fp_line
			(start 0.120396 0.3048)
			(end 0.120396 0.2794)
			(stroke
				(width 0.1)
				(type default)
			)
			(layer "F.Fab")
		)
		(fp_line
			(start -0.12065 0.3048)
			(end -0.67945 0.3048)
			(stroke
				(width 0.1)
				(type default)
			)
			(layer "F.Fab")
		)
		(fp_line
			(start -0.67945 0.3048)
			(end -0.67945 -0.305054)
			(stroke
				(width 0.1)
				(type default)
			)
			(layer "F.Fab")
		)
		(pad "1" smd circle
			(at -0.40005 0 90)
			(size 0 0)
			(layers "F.Cu" "F.Mask" "F.Paste")
			(net "SSD1_AUX_P3V3_EN_R")
		)
		(pad "2" smd circle
			(at 0.40005 0 90)
			(size 0 0)
			(layers "F.Cu" "F.Mask" "F.Paste")
			(net "SSD1_AUX_P3V3_EN")
		)
	)
	(footprint ""
		(layer "F.Cu")
		(at 7.103364 -59.571636 90)
		(property "Reference" "PR257"
			(at 0 0 90)
			(layer "F.SilkS")
			(hide yes)
			(effects
				(font
					(size 1.27 1.27)
				)
			)
		)
		(property "Value" ""
			(at 0 0 90)
			(layer "F.Fab")
			(effects
				(font
					(size 1.27 1.27)
				)
			)
		)
		(duplicate_pad_numbers_are_jumpers no)
		(fp_line
			(start 0.7874 -0.4064)
			(end 0.7874 0.4064)
			(stroke
				(width 0.1524)
				(type default)
			)
			(layer "F.SilkS")
		)
		(fp_line
			(start -0.7874 -0.4064)
			(end 0.7874 -0.4064)
			(stroke
				(width 0.1524)
				(type default)
			)
			(layer "F.SilkS")
		)
		(fp_line
			(start 0.7874 0.4064)
			(end -0.7874 0.4064)
			(stroke
				(width 0.1524)
				(type default)
			)
			(layer "F.SilkS")
		)
		(fp_line
			(start -0.7874 0.4064)
			(end -0.7874 -0.4064)
			(stroke
				(width 0.1524)
				(type default)
			)
			(layer "F.SilkS")
		)
		(fp_line
			(start -0.12065 -0.305054)
			(end -0.12065 -0.2794)
			(stroke
				(width 0.1)
				(type default)
			)
			(layer "F.Fab")
		)
		(fp_line
			(start -0.67945 -0.305054)
			(end -0.12065 -0.305054)
			(stroke
				(width 0.1)
				(type default)
			)
			(layer "F.Fab")
		)
		(fp_line
			(start 0.67945 -0.3048)
			(end 0.67945 0.3048)
			(stroke
				(width 0.1)
				(type default)
			)
			(layer "F.Fab")
		)
		(fp_line
			(start 0.12065 -0.3048)
			(end 0.67945 -0.3048)
			(stroke
				(width 0.1)
				(type default)
			)
			(layer "F.Fab")
		)
		(fp_line
			(start 0.12065 -0.2794)
			(end 0.12065 -0.3048)
			(stroke
				(width 0.1)
				(type default)
			)
			(layer "F.Fab")
		)
		(fp_line
			(start -0.12065 -0.2794)
			(end 0.12065 -0.2794)
			(stroke
				(width 0.1)
				(type default)
			)
			(layer "F.Fab")
		)
		(fp_line
			(start 0.120396 0.2794)
			(end -0.12065 0.2794)
			(stroke
				(width 0.1)
				(type default)
			)
			(layer "F.Fab")
		)
		(fp_line
			(start -0.12065 0.2794)
			(end -0.12065 0.3048)
			(stroke
				(width 0.1)
				(type default)
			)
			(layer "F.Fab")
		)
		(fp_line
			(start 0.67945 0.3048)
			(end 0.120396 0.3048)
			(stroke
				(width 0.1)
				(type default)
			)
			(layer "F.Fab")
		)
		(fp_line
			(start 0.120396 0.3048)
			(end 0.120396 0.2794)
			(stroke
				(width 0.1)
				(type default)
			)
			(layer "F.Fab")
		)
		(fp_line
			(start -0.12065 0.3048)
			(end -0.67945 0.3048)
			(stroke
				(width 0.1)
				(type default)
			)
			(layer "F.Fab")
		)
		(fp_line
			(start -0.67945 0.3048)
			(end -0.67945 -0.305054)
			(stroke
				(width 0.1)
				(type default)
			)
			(layer "F.Fab")
		)
		(pad "1" smd circle
			(at -0.40005 0 90)
			(size 0 0)
			(layers "F.Cu" "F.Mask" "F.Paste")
			(net "P3V3_SSD0_OCP")
		)
		(pad "2" smd circle
			(at 0.40005 0 90)
			(size 0 0)
			(layers "F.Cu" "F.Mask" "F.Paste")
			(net "GND")
		)
	)
	(footprint ""
		(layer "F.Cu")
		(at 454.125838 -314.192158 180)
		(property "Reference" "PC269"
			(at 0 0 180)
			(layer "F.SilkS")
			(hide yes)
			(effects
				(font
					(size 1.27 1.27)
				)
			)
		)
		(property "Value" ""
			(at 0 0 180)
			(layer "F.Fab")
			(effects
				(font
					(size 1.27 1.27)
				)
			)
		)
		(duplicate_pad_numbers_are_jumpers no)
		(fp_line
			(start 1.524 0.762)
			(end -1.524 0.762)
			(stroke
				(width 0.1524)
				(type default)
			)
			(layer "F.SilkS")
		)
		(fp_line
			(start 1.524 -0.762)
			(end 1.524 0.762)
			(stroke
				(width 0.1524)
				(type default)
			)
			(layer "F.SilkS")
		)
		(fp_line
			(start -1.524 0.762)
			(end -1.524 -0.762)
			(stroke
				(width 0.1524)
				(type default)
			)
			(layer "F.SilkS")
		)
		(fp_line
			(start -1.524 -0.762)
			(end 1.524 -0.762)
			(stroke
				(width 0.1524)
				(type default)
			)
			(layer "F.SilkS")
		)
		(fp_line
			(start 1.1049 0.724916)
			(end 1.1049 -0.724916)
			(stroke
				(width 0.1)
				(type default)
			)
			(layer "F.Fab")
		)
		(fp_line
			(start 1.1049 -0.724916)
			(end -1.1049 -0.724916)
			(stroke
				(width 0.1)
				(type default)
			)
			(layer "F.Fab")
		)
		(fp_line
			(start -1.1049 0.724916)
			(end 1.1049 0.724916)
			(stroke
				(width 0.1)
				(type default)
			)
			(layer "F.Fab")
		)
		(fp_line
			(start -1.1049 -0.724916)
			(end -1.1049 0.724916)
			(stroke
				(width 0.1)
				(type default)
			)
			(layer "F.Fab")
		)
		(pad "1" smd rect
			(at -0.889 0)
			(size 1.016 1.27)
			(layers "F.Cu" "F.Mask" "F.Paste")
			(net "SW_P12V_P1V25_PEX3_FLT")
		)
		(pad "2" smd rect
			(at 0.889 0)
			(size 1.016 1.27)
			(layers "F.Cu" "F.Mask" "F.Paste")
			(net "GND")
		)
	)
	(footprint ""
		(layer "F.Cu")
		(at 227.31476 -316.176914)
		(property "Reference" "PC227"
			(at 0 0 0)
			(layer "F.SilkS")
			(hide yes)
			(effects
				(font
					(size 1.27 1.27)
				)
			)
		)
		(property "Value" ""
			(at 0 0 0)
			(layer "F.Fab")
			(effects
				(font
					(size 1.27 1.27)
				)
			)
		)
		(duplicate_pad_numbers_are_jumpers no)
		(fp_line
			(start -1.524 -0.762)
			(end 1.524 -0.762)
			(stroke
				(width 0.1524)
				(type default)
			)
			(layer "F.SilkS")
		)
		(fp_line
			(start -1.524 0.762)
			(end -1.524 -0.762)
			(stroke
				(width 0.1524)
				(type default)
			)
			(layer "F.SilkS")
		)
		(fp_line
			(start 1.524 -0.762)
			(end 1.524 0.762)
			(stroke
				(width 0.1524)
				(type default)
			)
			(layer "F.SilkS")
		)
		(fp_line
			(start 1.524 0.762)
			(end -1.524 0.762)
			(stroke
				(width 0.1524)
				(type default)
			)
			(layer "F.SilkS")
		)
		(fp_line
			(start -1.1049 -0.724916)
			(end -1.1049 0.724916)
			(stroke
				(width 0.1)
				(type default)
			)
			(layer "F.Fab")
		)
		(fp_line
			(start -1.1049 0.724916)
			(end 1.1049 0.724916)
			(stroke
				(width 0.1)
				(type default)
			)
			(layer "F.Fab")
		)
		(fp_line
			(start 1.1049 -0.724916)
			(end -1.1049 -0.724916)
			(stroke
				(width 0.1)
				(type default)
			)
			(layer "F.Fab")
		)
		(fp_line
			(start 1.1049 0.724916)
			(end 1.1049 -0.724916)
			(stroke
				(width 0.1)
				(type default)
			)
			(layer "F.Fab")
		)
		(pad "1" smd rect
			(at -0.889 0 180)
			(size 1.016 1.27)
			(layers "F.Cu" "F.Mask" "F.Paste")
			(net "SW_P12V_P1V25_PEX1_FLT")
		)
		(pad "2" smd rect
			(at 0.889 0 180)
			(size 1.016 1.27)
			(layers "F.Cu" "F.Mask" "F.Paste")
			(net "GND")
		)
	)
	(footprint ""
		(layer "F.Cu")
		(at 211.051902 -235.756958 90)
		(property "Reference" "R6358"
			(at 0 0 90)
			(layer "F.SilkS")
			(hide yes)
			(effects
				(font
					(size 1.27 1.27)
				)
			)
		)
		(property "Value" ""
			(at 0 0 90)
			(layer "F.Fab")
			(effects
				(font
					(size 1.27 1.27)
				)
			)
		)
		(duplicate_pad_numbers_are_jumpers no)
		(fp_line
			(start 0.7874 -0.4064)
			(end 0.7874 0.4064)
			(stroke
				(width 0.1524)
				(type default)
			)
			(layer "F.SilkS")
		)
		(fp_line
			(start -0.7874 -0.4064)
			(end 0.7874 -0.4064)
			(stroke
				(width 0.1524)
				(type default)
			)
			(layer "F.SilkS")
		)
		(fp_line
			(start 0.7874 0.4064)
			(end -0.7874 0.4064)
			(stroke
				(width 0.1524)
				(type default)
			)
			(layer "F.SilkS")
		)
		(fp_line
			(start -0.7874 0.4064)
			(end -0.7874 -0.4064)
			(stroke
				(width 0.1524)
				(type default)
			)
			(layer "F.SilkS")
		)
		(fp_line
			(start -0.12065 -0.305054)
			(end -0.12065 -0.2794)
			(stroke
				(width 0.1)
				(type default)
			)
			(layer "F.Fab")
		)
		(fp_line
			(start -0.67945 -0.305054)
			(end -0.12065 -0.305054)
			(stroke
				(width 0.1)
				(type default)
			)
			(layer "F.Fab")
		)
		(fp_line
			(start 0.67945 -0.3048)
			(end 0.67945 0.3048)
			(stroke
				(width 0.1)
				(type default)
			)
			(layer "F.Fab")
		)
		(fp_line
			(start 0.12065 -0.3048)
			(end 0.67945 -0.3048)
			(stroke
				(width 0.1)
				(type default)
			)
			(layer "F.Fab")
		)
		(fp_line
			(start 0.12065 -0.2794)
			(end 0.12065 -0.3048)
			(stroke
				(width 0.1)
				(type default)
			)
			(layer "F.Fab")
		)
		(fp_line
			(start -0.12065 -0.2794)
			(end 0.12065 -0.2794)
			(stroke
				(width 0.1)
				(type default)
			)
			(layer "F.Fab")
		)
		(fp_line
			(start 0.120396 0.2794)
			(end -0.12065 0.2794)
			(stroke
				(width 0.1)
				(type default)
			)
			(layer "F.Fab")
		)
		(fp_line
			(start -0.12065 0.2794)
			(end -0.12065 0.3048)
			(stroke
				(width 0.1)
				(type default)
			)
			(layer "F.Fab")
		)
		(fp_line
			(start 0.67945 0.3048)
			(end 0.120396 0.3048)
			(stroke
				(width 0.1)
				(type default)
			)
			(layer "F.Fab")
		)
		(fp_line
			(start 0.120396 0.3048)
			(end 0.120396 0.2794)
			(stroke
				(width 0.1)
				(type default)
			)
			(layer "F.Fab")
		)
		(fp_line
			(start -0.12065 0.3048)
			(end -0.67945 0.3048)
			(stroke
				(width 0.1)
				(type default)
			)
			(layer "F.Fab")
		)
		(fp_line
			(start -0.67945 0.3048)
			(end -0.67945 -0.305054)
			(stroke
				(width 0.1)
				(type default)
			)
			(layer "F.Fab")
		)
		(pad "1" smd circle
			(at -0.40005 0 90)
			(size 0 0)
			(layers "F.Cu" "F.Mask" "F.Paste")
			(net "SMB_PEX_LS_R_SCL")
		)
		(pad "2" smd circle
			(at 0.40005 0 90)
			(size 0 0)
			(layers "F.Cu" "F.Mask" "F.Paste")
			(net "SMB_PEX_LS_SCL")
		)
	)
	(footprint ""
		(layer "F.Cu")
		(at 260.695186 -35.48253)
		(property "Reference" "U390"
			(at -2.528316 0.78613 90)
			(unlocked yes)
			(layer "F.SilkS")
			(effects
				(font
					(size 0.7874 0.5842)
					(thickness 0.1524)
				)
				(justify left)
			)
		)
		(property "Value" ""
			(at 0 0 0)
			(layer "F.Fab")
			(effects
				(font
					(size 1.27 1.27)
				)
			)
		)
		(duplicate_pad_numbers_are_jumpers no)
		(fp_line
			(start -1.3462 -1.1938)
			(end -1.3462 1.1684)
			(stroke
				(width 0.1524)
				(type default)
			)
			(layer "F.SilkS")
		)
		(fp_line
			(start -1.3462 1.1938)
			(end 1.3462 1.1938)
			(stroke
				(width 0.1524)
				(type default)
			)
			(layer "F.SilkS")
		)
		(fp_line
			(start 1.3462 -1.1938)
			(end -1.3462 -1.1938)
			(stroke
				(width 0.1524)
				(type default)
			)
			(layer "F.SilkS")
		)
		(fp_line
			(start 1.3462 1.1938)
			(end 1.3462 -1.1938)
			(stroke
				(width 0.1524)
				(type default)
			)
			(layer "F.SilkS")
		)
		(fp_poly
			(pts
				(xy -1.447038 -0.760476) (xy -2.052066 -0.457962) (xy -2.052066 -1.06299)
			)
			(stroke
				(width 0)
				(type default)
			)
			(fill yes)
			(layer "F.SilkS")
		)
		(fp_line
			(start -0.674878 -1.124966)
			(end -0.674878 1.124966)
			(stroke
				(width 0.1)
				(type default)
			)
			(layer "F.Fab")
		)
		(fp_line
			(start -0.674878 1.124966)
			(end 0.674878 1.124966)
			(stroke
				(width 0.1)
				(type default)
			)
			(layer "F.Fab")
		)
		(fp_line
			(start 0.674878 -1.124966)
			(end -0.674878 -1.124966)
			(stroke
				(width 0.1)
				(type default)
			)
			(layer "F.Fab")
		)
		(fp_line
			(start 0.674878 1.124966)
			(end 0.674878 -1.124966)
			(stroke
				(width 0.1)
				(type default)
			)
			(layer "F.Fab")
		)
		(fp_poly
			(pts
				(xy -1.447038 -0.760476) (xy -2.052066 -0.457962) (xy -2.052066 -1.06299)
			)
			(stroke
				(width 0)
				(type default)
			)
			(fill yes)
			(layer "F.Fab")
		)
		(pad "1" smd rect
			(at -0.899922 -0.750062)
			(size 0.6096 0.6096)
			(layers "F.Cu" "F.Mask" "F.Paste")
			(net "PWRGD_P3V3_SSD9_R")
		)
		(pad "2" smd rect
			(at -0.899922 0 90)
			(size 0.4064 0.6096)
			(layers "F.Cu" "F.Mask" "F.Paste")
			(net "RST_SMB_SSD9_N")
		)
		(pad "3" smd rect
			(at -0.899922 0.750062)
			(size 0.6096 0.6096)
			(layers "F.Cu" "F.Mask" "F.Paste")
			(net "GND")
		)
		(pad "4" smd rect
			(at 0.899922 0.750062)
			(size 0.6096 0.6096)
			(layers "F.Cu" "F.Mask" "F.Paste")
			(net "RST_SMB_SSD9_ISO_N")
		)
		(pad "5" smd rect
			(at 0.899922 -0.750062)
			(size 0.6096 0.6096)
			(layers "F.Cu" "F.Mask" "F.Paste")
			(net "P3V3_AUX")
		)
	)
	(footprint ""
		(layer "F.Cu")
		(at 386.90804 -156.3624 180)
		(property "Reference" "R319"
			(at 0 0 180)
			(layer "F.SilkS")
			(hide yes)
			(effects
				(font
					(size 1.27 1.27)
				)
			)
		)
		(property "Value" ""
			(at 0 0 180)
			(layer "F.Fab")
			(effects
				(font
					(size 1.27 1.27)
				)
			)
		)
		(duplicate_pad_numbers_are_jumpers no)
		(fp_line
			(start 0.7874 0.4064)
			(end -0.7874 0.4064)
			(stroke
				(width 0.1524)
				(type default)
			)
			(layer "F.SilkS")
		)
		(fp_line
			(start 0.7874 -0.4064)
			(end 0.7874 0.4064)
			(stroke
				(width 0.1524)
				(type default)
			)
			(layer "F.SilkS")
		)
		(fp_line
			(start -0.7874 0.4064)
			(end -0.7874 -0.4064)
			(stroke
				(width 0.1524)
				(type default)
			)
			(layer "F.SilkS")
		)
		(fp_line
			(start -0.7874 -0.4064)
			(end 0.7874 -0.4064)
			(stroke
				(width 0.1524)
				(type default)
			)
			(layer "F.SilkS")
		)
		(fp_line
			(start 0.67945 0.3048)
			(end 0.120396 0.3048)
			(stroke
				(width 0.1)
				(type default)
			)
			(layer "F.Fab")
		)
		(fp_line
			(start 0.67945 -0.3048)
			(end 0.67945 0.3048)
			(stroke
				(width 0.1)
				(type default)
			)
			(layer "F.Fab")
		)
		(fp_line
			(start 0.12065 -0.2794)
			(end 0.12065 -0.3048)
			(stroke
				(width 0.1)
				(type default)
			)
			(layer "F.Fab")
		)
		(fp_line
			(start 0.12065 -0.3048)
			(end 0.67945 -0.3048)
			(stroke
				(width 0.1)
				(type default)
			)
			(layer "F.Fab")
		)
		(fp_line
			(start 0.120396 0.3048)
			(end 0.120396 0.2794)
			(stroke
				(width 0.1)
				(type default)
			)
			(layer "F.Fab")
		)
		(fp_line
			(start 0.120396 0.2794)
			(end -0.12065 0.2794)
			(stroke
				(width 0.1)
				(type default)
			)
			(layer "F.Fab")
		)
		(fp_line
			(start -0.12065 0.3048)
			(end -0.67945 0.3048)
			(stroke
				(width 0.1)
				(type default)
			)
			(layer "F.Fab")
		)
		(fp_line
			(start -0.12065 0.2794)
			(end -0.12065 0.3048)
			(stroke
				(width 0.1)
				(type default)
			)
			(layer "F.Fab")
		)
		(fp_line
			(start -0.12065 -0.2794)
			(end 0.12065 -0.2794)
			(stroke
				(width 0.1)
				(type default)
			)
			(layer "F.Fab")
		)
		(fp_line
			(start -0.12065 -0.305054)
			(end -0.12065 -0.2794)
			(stroke
				(width 0.1)
				(type default)
			)
			(layer "F.Fab")
		)
		(fp_line
			(start -0.67945 0.3048)
			(end -0.67945 -0.305054)
			(stroke
				(width 0.1)
				(type default)
			)
			(layer "F.Fab")
		)
		(fp_line
			(start -0.67945 -0.305054)
			(end -0.12065 -0.305054)
			(stroke
				(width 0.1)
				(type default)
			)
			(layer "F.Fab")
		)
		(pad "1" smd circle
			(at -0.40005 0 180)
			(size 0 0)
			(layers "F.Cu" "F.Mask" "F.Paste")
			(net "NIC6_DATA_OUT")
		)
		(pad "2" smd circle
			(at 0.40005 0 180)
			(size 0 0)
			(layers "F.Cu" "F.Mask" "F.Paste")
			(net "GND")
		)
	)
)
